(kicad_pcb
	(version 20260206)
	(generator "pcbnew")
	(generator_version "10.0")
	(general
		(thickness 1.6)
		(legacy_teardrops no)
	)
	(paper "A4")
	(title_block
		(title "01162023_DA0F0TEBIF0_F0T_Expander_BD_F_brd_V02_OCP.brd")
		(comment 1 "Grand Teton / footprints 313-320 of 9728")
	)
	(layers
		(0 "F.Cu" signal "TOP")
		(4 "In1.Cu" signal "GND")
		(6 "In2.Cu" signal "VCC")
		(8 "In3.Cu" signal "VCC1")
		(10 "In4.Cu" signal "GND1")
		(12 "In5.Cu" signal "IN1")
		(14 "In6.Cu" signal "GND2")
		(16 "In7.Cu" signal "IN2")
		(18 "In8.Cu" signal "GND3")
		(20 "In9.Cu" signal "IN3")
		(22 "In10.Cu" signal "GND4")
		(24 "In11.Cu" signal "IN4")
		(26 "In12.Cu" signal "GND5")
		(28 "In13.Cu" signal "IN5")
		(30 "In14.Cu" signal "GND6")
		(32 "In15.Cu" signal "IN6")
		(34 "In16.Cu" signal "GND7")
		(2 "B.Cu" signal "BOTTOM")
		(9 "F.Adhes" user "F.Adhesive")
		(11 "B.Adhes" user "B.Adhesive")
		(13 "F.Paste" user "Package Geometry/Pastemask Top")
		(15 "B.Paste" user "Package Geometry/Pastemask Bottom")
		(5 "F.SilkS" user "Ref Des/Silkscreen Top")
		(7 "B.SilkS" user "Ref Des/Silkscreen Bottom")
		(1 "F.Mask" user "Board Geometry/Soldermask Top")
		(3 "B.Mask" user "Board Geometry/Soldermask Bottom")
		(17 "Dwgs.User" user "User.Drawings")
		(19 "Cmts.User" user "User.Comments")
		(21 "Eco1.User" user "User.Eco1")
		(23 "Eco2.User" user "User.Eco2")
		(25 "Edge.Cuts" user "Board Geometry/Outline")
		(27 "Margin" user)
		(31 "F.CrtYd" user "Package Geometry/Place Bound Top")
		(29 "B.CrtYd" user "Package Geometry/Place Bound Bottom")
		(35 "F.Fab" user "Ref Des/Assembly Top")
		(33 "B.Fab" user "Ref Des/Assembly Bottom")
	)
	(footprint ""
		(layer "F.Cu")
		(at 27.390344 -250.070874 -90)
		(property "Reference" "R1157"
			(at 0 0 270)
			(layer "F.SilkS")
			(hide yes)
			(effects
				(font
					(size 1.27 1.27)
				)
			)
		)
		(property "Value" ""
			(at 0 0 270)
			(layer "F.Fab")
			(effects
				(font
					(size 1.27 1.27)
				)
			)
		)
		(duplicate_pad_numbers_are_jumpers no)
		(fp_line
			(start -0.7874 0.4064)
			(end -0.7874 -0.4064)
			(stroke
				(width 0.1524)
				(type default)
			)
			(layer "F.SilkS")
		)
		(fp_line
			(start 0.7874 0.4064)
			(end -0.7874 0.4064)
			(stroke
				(width 0.1524)
				(type default)
			)
			(layer "F.SilkS")
		)
		(fp_line
			(start -0.7874 -0.4064)
			(end 0.7874 -0.4064)
			(stroke
				(width 0.1524)
				(type default)
			)
			(layer "F.SilkS")
		)
		(fp_line
			(start 0.7874 -0.4064)
			(end 0.7874 0.4064)
			(stroke
				(width 0.1524)
				(type default)
			)
			(layer "F.SilkS")
		)
		(fp_line
			(start -0.67945 0.3048)
			(end -0.67945 -0.305054)
			(stroke
				(width 0.1)
				(type default)
			)
			(layer "F.Fab")
		)
		(fp_line
			(start -0.12065 0.3048)
			(end -0.67945 0.3048)
			(stroke
				(width 0.1)
				(type default)
			)
			(layer "F.Fab")
		)
		(fp_line
			(start 0.120396 0.3048)
			(end 0.120396 0.2794)
			(stroke
				(width 0.1)
				(type default)
			)
			(layer "F.Fab")
		)
		(fp_line
			(start 0.67945 0.3048)
			(end 0.120396 0.3048)
			(stroke
				(width 0.1)
				(type default)
			)
			(layer "F.Fab")
		)
		(fp_line
			(start -0.12065 0.2794)
			(end -0.12065 0.3048)
			(stroke
				(width 0.1)
				(type default)
			)
			(layer "F.Fab")
		)
		(fp_line
			(start 0.120396 0.2794)
			(end -0.12065 0.2794)
			(stroke
				(width 0.1)
				(type default)
			)
			(layer "F.Fab")
		)
		(fp_line
			(start -0.12065 -0.2794)
			(end 0.12065 -0.2794)
			(stroke
				(width 0.1)
				(type default)
			)
			(layer "F.Fab")
		)
		(fp_line
			(start 0.12065 -0.2794)
			(end 0.12065 -0.3048)
			(stroke
				(width 0.1)
				(type default)
			)
			(layer "F.Fab")
		)
		(fp_line
			(start 0.12065 -0.3048)
			(end 0.67945 -0.3048)
			(stroke
				(width 0.1)
				(type default)
			)
			(layer "F.Fab")
		)
		(fp_line
			(start 0.67945 -0.3048)
			(end 0.67945 0.3048)
			(stroke
				(width 0.1)
				(type default)
			)
			(layer "F.Fab")
		)
		(fp_line
			(start -0.67945 -0.305054)
			(end -0.12065 -0.305054)
			(stroke
				(width 0.1)
				(type default)
			)
			(layer "F.Fab")
		)
		(fp_line
			(start -0.12065 -0.305054)
			(end -0.12065 -0.2794)
			(stroke
				(width 0.1)
				(type default)
			)
			(layer "F.Fab")
		)
		(pad "1" smd circle
			(at -0.40005 0 270)
			(size 0 0)
			(layers "F.Cu" "F.Mask" "F.Paste")
			(net "PEX0_MODE_SEL5")
		)
		(pad "2" smd circle
			(at 0.40005 0 270)
			(size 0 0)
			(layers "F.Cu" "F.Mask" "F.Paste")
			(net "P1V8_PEX")
		)
	)
	(footprint ""
		(layer "F.Cu")
		(at 457.935838 -312.795158)
		(property "Reference" "PC265"
			(at 0 0 0)
			(layer "F.SilkS")
			(hide yes)
			(effects
				(font
					(size 1.27 1.27)
				)
			)
		)
		(property "Value" ""
			(at 0 0 0)
			(layer "F.Fab")
			(effects
				(font
					(size 1.27 1.27)
				)
			)
		)
		(duplicate_pad_numbers_are_jumpers no)
		(fp_line
			(start -1.524 -0.762)
			(end 1.524 -0.762)
			(stroke
				(width 0.1524)
				(type default)
			)
			(layer "F.SilkS")
		)
		(fp_line
			(start -1.524 0.762)
			(end -1.524 -0.762)
			(stroke
				(width 0.1524)
				(type default)
			)
			(layer "F.SilkS")
		)
		(fp_line
			(start 1.524 -0.762)
			(end 1.524 0.762)
			(stroke
				(width 0.1524)
				(type default)
			)
			(layer "F.SilkS")
		)
		(fp_line
			(start 1.524 0.762)
			(end -1.524 0.762)
			(stroke
				(width 0.1524)
				(type default)
			)
			(layer "F.SilkS")
		)
		(fp_line
			(start -1.1049 -0.724916)
			(end -1.1049 0.724916)
			(stroke
				(width 0.1)
				(type default)
			)
			(layer "F.Fab")
		)
		(fp_line
			(start -1.1049 0.724916)
			(end 1.1049 0.724916)
			(stroke
				(width 0.1)
				(type default)
			)
			(layer "F.Fab")
		)
		(fp_line
			(start 1.1049 -0.724916)
			(end -1.1049 -0.724916)
			(stroke
				(width 0.1)
				(type default)
			)
			(layer "F.Fab")
		)
		(fp_line
			(start 1.1049 0.724916)
			(end 1.1049 -0.724916)
			(stroke
				(width 0.1)
				(type default)
			)
			(layer "F.Fab")
		)
		(pad "1" smd rect
			(at -0.889 0 180)
			(size 1.016 1.27)
			(layers "F.Cu" "F.Mask" "F.Paste")
			(net "SW_P12V_P1V25_PEX3_FLT")
		)
		(pad "2" smd rect
			(at 0.889 0 180)
			(size 1.016 1.27)
			(layers "F.Cu" "F.Mask" "F.Paste")
			(net "GND")
		)
	)
	(footprint ""
		(layer "F.Cu")
		(at 207.473804 -298.885102 -90)
		(property "Reference" "R4015"
			(at 0 0 270)
			(layer "F.SilkS")
			(hide yes)
			(effects
				(font
					(size 1.27 1.27)
				)
			)
		)
		(property "Value" ""
			(at 0 0 270)
			(layer "F.Fab")
			(effects
				(font
					(size 1.27 1.27)
				)
			)
		)
		(duplicate_pad_numbers_are_jumpers no)
		(fp_line
			(start -0.7874 0.4064)
			(end -0.7874 -0.4064)
			(stroke
				(width 0.1524)
				(type default)
			)
			(layer "F.SilkS")
		)
		(fp_line
			(start 0.7874 0.4064)
			(end -0.7874 0.4064)
			(stroke
				(width 0.1524)
				(type default)
			)
			(layer "F.SilkS")
		)
		(fp_line
			(start -0.7874 -0.4064)
			(end 0.7874 -0.4064)
			(stroke
				(width 0.1524)
				(type default)
			)
			(layer "F.SilkS")
		)
		(fp_line
			(start 0.7874 -0.4064)
			(end 0.7874 0.4064)
			(stroke
				(width 0.1524)
				(type default)
			)
			(layer "F.SilkS")
		)
		(fp_line
			(start -0.67945 0.3048)
			(end -0.67945 -0.305054)
			(stroke
				(width 0.1)
				(type default)
			)
			(layer "F.Fab")
		)
		(fp_line
			(start -0.12065 0.3048)
			(end -0.67945 0.3048)
			(stroke
				(width 0.1)
				(type default)
			)
			(layer "F.Fab")
		)
		(fp_line
			(start 0.120396 0.3048)
			(end 0.120396 0.2794)
			(stroke
				(width 0.1)
				(type default)
			)
			(layer "F.Fab")
		)
		(fp_line
			(start 0.67945 0.3048)
			(end 0.120396 0.3048)
			(stroke
				(width 0.1)
				(type default)
			)
			(layer "F.Fab")
		)
		(fp_line
			(start -0.12065 0.2794)
			(end -0.12065 0.3048)
			(stroke
				(width 0.1)
				(type default)
			)
			(layer "F.Fab")
		)
		(fp_line
			(start 0.120396 0.2794)
			(end -0.12065 0.2794)
			(stroke
				(width 0.1)
				(type default)
			)
			(layer "F.Fab")
		)
		(fp_line
			(start -0.12065 -0.2794)
			(end 0.12065 -0.2794)
			(stroke
				(width 0.1)
				(type default)
			)
			(layer "F.Fab")
		)
		(fp_line
			(start 0.12065 -0.2794)
			(end 0.12065 -0.3048)
			(stroke
				(width 0.1)
				(type default)
			)
			(layer "F.Fab")
		)
		(fp_line
			(start 0.12065 -0.3048)
			(end 0.67945 -0.3048)
			(stroke
				(width 0.1)
				(type default)
			)
			(layer "F.Fab")
		)
		(fp_line
			(start 0.67945 -0.3048)
			(end 0.67945 0.3048)
			(stroke
				(width 0.1)
				(type default)
			)
			(layer "F.Fab")
		)
		(fp_line
			(start -0.67945 -0.305054)
			(end -0.12065 -0.305054)
			(stroke
				(width 0.1)
				(type default)
			)
			(layer "F.Fab")
		)
		(fp_line
			(start -0.12065 -0.305054)
			(end -0.12065 -0.2794)
			(stroke
				(width 0.1)
				(type default)
			)
			(layer "F.Fab")
		)
		(pad "1" smd circle
			(at -0.40005 0 270)
			(size 0 0)
			(layers "F.Cu" "F.Mask" "F.Paste")
			(net "P1V8_PEX")
		)
		(pad "2" smd circle
			(at 0.40005 0 270)
			(size 0 0)
			(layers "F.Cu" "F.Mask" "F.Paste")
			(net "I2C_PEX1_HOST_R_SCL")
		)
	)
	(footprint ""
		(layer "F.Cu")
		(at 278.105616 -405.074374 90)
		(property "Reference" "R1819"
			(at 0 0 90)
			(layer "F.SilkS")
			(hide yes)
			(effects
				(font
					(size 1.27 1.27)
				)
			)
		)
		(property "Value" ""
			(at 0 0 90)
			(layer "F.Fab")
			(effects
				(font
					(size 1.27 1.27)
				)
			)
		)
		(duplicate_pad_numbers_are_jumpers no)
		(fp_line
			(start 0.7874 -0.4064)
			(end 0.7874 0.4064)
			(stroke
				(width 0.1524)
				(type default)
			)
			(layer "F.SilkS")
		)
		(fp_line
			(start -0.7874 -0.4064)
			(end 0.7874 -0.4064)
			(stroke
				(width 0.1524)
				(type default)
			)
			(layer "F.SilkS")
		)
		(fp_line
			(start 0.7874 0.4064)
			(end -0.7874 0.4064)
			(stroke
				(width 0.1524)
				(type default)
			)
			(layer "F.SilkS")
		)
		(fp_line
			(start -0.7874 0.4064)
			(end -0.7874 -0.4064)
			(stroke
				(width 0.1524)
				(type default)
			)
			(layer "F.SilkS")
		)
		(fp_line
			(start -0.12065 -0.305054)
			(end -0.12065 -0.2794)
			(stroke
				(width 0.1)
				(type default)
			)
			(layer "F.Fab")
		)
		(fp_line
			(start -0.67945 -0.305054)
			(end -0.12065 -0.305054)
			(stroke
				(width 0.1)
				(type default)
			)
			(layer "F.Fab")
		)
		(fp_line
			(start 0.67945 -0.3048)
			(end 0.67945 0.3048)
			(stroke
				(width 0.1)
				(type default)
			)
			(layer "F.Fab")
		)
		(fp_line
			(start 0.12065 -0.3048)
			(end 0.67945 -0.3048)
			(stroke
				(width 0.1)
				(type default)
			)
			(layer "F.Fab")
		)
		(fp_line
			(start 0.12065 -0.2794)
			(end 0.12065 -0.3048)
			(stroke
				(width 0.1)
				(type default)
			)
			(layer "F.Fab")
		)
		(fp_line
			(start -0.12065 -0.2794)
			(end 0.12065 -0.2794)
			(stroke
				(width 0.1)
				(type default)
			)
			(layer "F.Fab")
		)
		(fp_line
			(start 0.120396 0.2794)
			(end -0.12065 0.2794)
			(stroke
				(width 0.1)
				(type default)
			)
			(layer "F.Fab")
		)
		(fp_line
			(start -0.12065 0.2794)
			(end -0.12065 0.3048)
			(stroke
				(width 0.1)
				(type default)
			)
			(layer "F.Fab")
		)
		(fp_line
			(start 0.67945 0.3048)
			(end 0.120396 0.3048)
			(stroke
				(width 0.1)
				(type default)
			)
			(layer "F.Fab")
		)
		(fp_line
			(start 0.120396 0.3048)
			(end 0.120396 0.2794)
			(stroke
				(width 0.1)
				(type default)
			)
			(layer "F.Fab")
		)
		(fp_line
			(start -0.12065 0.3048)
			(end -0.67945 0.3048)
			(stroke
				(width 0.1)
				(type default)
			)
			(layer "F.Fab")
		)
		(fp_line
			(start -0.67945 0.3048)
			(end -0.67945 -0.305054)
			(stroke
				(width 0.1)
				(type default)
			)
			(layer "F.Fab")
		)
		(pad "1" smd circle
			(at -0.40005 0 90)
			(size 0 0)
			(layers "F.Cu" "F.Mask" "F.Paste")
			(net "BIC_SYS_READY_R_N")
		)
		(pad "2" smd circle
			(at 0.40005 0 90)
			(size 0 0)
			(layers "F.Cu" "F.Mask" "F.Paste")
			(net "BIC_SYS_READY_R1_N")
		)
	)
	(footprint ""
		(layer "F.Cu")
		(at 155.380436 -121.919746)
		(property "Reference" "C257"
			(at 0 0 0)
			(layer "F.SilkS")
			(hide yes)
			(effects
				(font
					(size 1.27 1.27)
				)
			)
		)
		(property "Value" ""
			(at 0 0 0)
			(layer "F.Fab")
			(effects
				(font
					(size 1.27 1.27)
				)
			)
		)
		(duplicate_pad_numbers_are_jumpers no)
		(fp_line
			(start -0.299974 -0.150114)
			(end 0.299974 -0.150114)
			(stroke
				(width 0.1)
				(type default)
			)
			(layer "F.Fab")
		)
		(fp_line
			(start -0.299974 0.150114)
			(end -0.299974 -0.150114)
			(stroke
				(width 0.1)
				(type default)
			)
			(layer "F.Fab")
		)
		(fp_line
			(start 0.299974 -0.150114)
			(end 0.299974 0.150114)
			(stroke
				(width 0.1)
				(type default)
			)
			(layer "F.Fab")
		)
		(fp_line
			(start 0.299974 0.150114)
			(end -0.299974 0.150114)
			(stroke
				(width 0.1)
				(type default)
			)
			(layer "F.Fab")
		)
		(pad "1" smd rect
			(at -0.2667 0)
			(size 0.3048 0.381)
			(layers "F.Cu" "F.Mask" "F.Paste")
			(net "P5E_PEX1_STN1_TX_DP<25>")
		)
		(pad "2" smd rect
			(at 0.2667 0)
			(size 0.3048 0.381)
			(layers "F.Cu" "F.Mask" "F.Paste")
			(net "P5E_PEX1_STN1_TX_C_DP<25>")
		)
	)
	(footprint ""
		(layer "F.Cu")
		(at 124.149612 -158.828994 180)
		(property "Reference" "R5832"
			(at 0 0 180)
			(layer "F.SilkS")
			(hide yes)
			(effects
				(font
					(size 1.27 1.27)
				)
			)
		)
		(property "Value" ""
			(at 0 0 180)
			(layer "F.Fab")
			(effects
				(font
					(size 1.27 1.27)
				)
			)
		)
		(duplicate_pad_numbers_are_jumpers no)
		(fp_line
			(start 0.7874 0.4064)
			(end -0.7874 0.4064)
			(stroke
				(width 0.1524)
				(type default)
			)
			(layer "F.SilkS")
		)
		(fp_line
			(start 0.7874 -0.4064)
			(end 0.7874 0.4064)
			(stroke
				(width 0.1524)
				(type default)
			)
			(layer "F.SilkS")
		)
		(fp_line
			(start -0.7874 0.4064)
			(end -0.7874 -0.4064)
			(stroke
				(width 0.1524)
				(type default)
			)
			(layer "F.SilkS")
		)
		(fp_line
			(start -0.7874 -0.4064)
			(end 0.7874 -0.4064)
			(stroke
				(width 0.1524)
				(type default)
			)
			(layer "F.SilkS")
		)
		(fp_line
			(start 0.67945 0.3048)
			(end 0.120396 0.3048)
			(stroke
				(width 0.1)
				(type default)
			)
			(layer "F.Fab")
		)
		(fp_line
			(start 0.67945 -0.3048)
			(end 0.67945 0.3048)
			(stroke
				(width 0.1)
				(type default)
			)
			(layer "F.Fab")
		)
		(fp_line
			(start 0.12065 -0.2794)
			(end 0.12065 -0.3048)
			(stroke
				(width 0.1)
				(type default)
			)
			(layer "F.Fab")
		)
		(fp_line
			(start 0.12065 -0.3048)
			(end 0.67945 -0.3048)
			(stroke
				(width 0.1)
				(type default)
			)
			(layer "F.Fab")
		)
		(fp_line
			(start 0.120396 0.3048)
			(end 0.120396 0.2794)
			(stroke
				(width 0.1)
				(type default)
			)
			(layer "F.Fab")
		)
		(fp_line
			(start 0.120396 0.2794)
			(end -0.12065 0.2794)
			(stroke
				(width 0.1)
				(type default)
			)
			(layer "F.Fab")
		)
		(fp_line
			(start -0.12065 0.3048)
			(end -0.67945 0.3048)
			(stroke
				(width 0.1)
				(type default)
			)
			(layer "F.Fab")
		)
		(fp_line
			(start -0.12065 0.2794)
			(end -0.12065 0.3048)
			(stroke
				(width 0.1)
				(type default)
			)
			(layer "F.Fab")
		)
		(fp_line
			(start -0.12065 -0.2794)
			(end 0.12065 -0.2794)
			(stroke
				(width 0.1)
				(type default)
			)
			(layer "F.Fab")
		)
		(fp_line
			(start -0.12065 -0.305054)
			(end -0.12065 -0.2794)
			(stroke
				(width 0.1)
				(type default)
			)
			(layer "F.Fab")
		)
		(fp_line
			(start -0.67945 0.3048)
			(end -0.67945 -0.305054)
			(stroke
				(width 0.1)
				(type default)
			)
			(layer "F.Fab")
		)
		(fp_line
			(start -0.67945 -0.305054)
			(end -0.12065 -0.305054)
			(stroke
				(width 0.1)
				(type default)
			)
			(layer "F.Fab")
		)
		(pad "1" smd circle
			(at -0.40005 0 180)
			(size 0 0)
			(layers "F.Cu" "F.Mask" "F.Paste")
			(net "PWRGD_P12V_NIC2_CO")
		)
		(pad "2" smd circle
			(at 0.40005 0 180)
			(size 0 0)
			(layers "F.Cu" "F.Mask" "F.Paste")
			(net "PWRGD_P12V_NIC2_R")
		)
	)
	(footprint ""
		(layer "F.Cu")
		(at 380.48946 -343.952322 90)
		(property "Reference" "C786"
			(at 0 0 90)
			(layer "F.SilkS")
			(hide yes)
			(effects
				(font
					(size 1.27 1.27)
				)
			)
		)
		(property "Value" ""
			(at 0 0 90)
			(layer "F.Fab")
			(effects
				(font
					(size 1.27 1.27)
				)
			)
		)
		(duplicate_pad_numbers_are_jumpers no)
		(fp_line
			(start 0.299974 -0.150114)
			(end 0.299974 0.150114)
			(stroke
				(width 0.1)
				(type default)
			)
			(layer "F.Fab")
		)
		(fp_line
			(start -0.299974 -0.150114)
			(end 0.299974 -0.150114)
			(stroke
				(width 0.1)
				(type default)
			)
			(layer "F.Fab")
		)
		(fp_line
			(start 0.299974 0.150114)
			(end -0.299974 0.150114)
			(stroke
				(width 0.1)
				(type default)
			)
			(layer "F.Fab")
		)
		(fp_line
			(start -0.299974 0.150114)
			(end -0.299974 -0.150114)
			(stroke
				(width 0.1)
				(type default)
			)
			(layer "F.Fab")
		)
		(pad "1" smd rect
			(at -0.2667 0 90)
			(size 0.3048 0.381)
			(layers "F.Cu" "F.Mask" "F.Paste")
			(net "P5E_PEX3_STN6_TX_DP<99>")
		)
		(pad "2" smd rect
			(at 0.2667 0 90)
			(size 0.3048 0.381)
			(layers "F.Cu" "F.Mask" "F.Paste")
			(net "P5E_PEX3_STN6_TX_C_DP<99>")
		)
	)
	(footprint ""
		(layer "F.Cu")
		(at 168.55948 -22.955504 90)
		(property "Reference" "R1672"
			(at 0 0 90)
			(layer "F.SilkS")
			(hide yes)
			(effects
				(font
					(size 1.27 1.27)
				)
			)
		)
		(property "Value" ""
			(at 0 0 90)
			(layer "F.Fab")
			(effects
				(font
					(size 1.27 1.27)
				)
			)
		)
		(duplicate_pad_numbers_are_jumpers no)
		(fp_line
			(start 0.7874 -0.4064)
			(end 0.7874 0.4064)
			(stroke
				(width 0.1524)
				(type default)
			)
			(layer "F.SilkS")
		)
		(fp_line
			(start -0.7874 -0.4064)
			(end 0.7874 -0.4064)
			(stroke
				(width 0.1524)
				(type default)
			)
			(layer "F.SilkS")
		)
		(fp_line
			(start 0.7874 0.4064)
			(end -0.7874 0.4064)
			(stroke
				(width 0.1524)
				(type default)
			)
			(layer "F.SilkS")
		)
		(fp_line
			(start -0.7874 0.4064)
			(end -0.7874 -0.4064)
			(stroke
				(width 0.1524)
				(type default)
			)
			(layer "F.SilkS")
		)
		(fp_line
			(start -0.12065 -0.305054)
			(end -0.12065 -0.2794)
			(stroke
				(width 0.1)
				(type default)
			)
			(layer "F.Fab")
		)
		(fp_line
			(start -0.67945 -0.305054)
			(end -0.12065 -0.305054)
			(stroke
				(width 0.1)
				(type default)
			)
			(layer "F.Fab")
		)
		(fp_line
			(start 0.67945 -0.3048)
			(end 0.67945 0.3048)
			(stroke
				(width 0.1)
				(type default)
			)
			(layer "F.Fab")
		)
		(fp_line
			(start 0.12065 -0.3048)
			(end 0.67945 -0.3048)
			(stroke
				(width 0.1)
				(type default)
			)
			(layer "F.Fab")
		)
		(fp_line
			(start 0.12065 -0.2794)
			(end 0.12065 -0.3048)
			(stroke
				(width 0.1)
				(type default)
			)
			(layer "F.Fab")
		)
		(fp_line
			(start -0.12065 -0.2794)
			(end 0.12065 -0.2794)
			(stroke
				(width 0.1)
				(type default)
			)
			(layer "F.Fab")
		)
		(fp_line
			(start 0.120396 0.2794)
			(end -0.12065 0.2794)
			(stroke
				(width 0.1)
				(type default)
			)
			(layer "F.Fab")
		)
		(fp_line
			(start -0.12065 0.2794)
			(end -0.12065 0.3048)
			(stroke
				(width 0.1)
				(type default)
			)
			(layer "F.Fab")
		)
		(fp_line
			(start 0.67945 0.3048)
			(end 0.120396 0.3048)
			(stroke
				(width 0.1)
				(type default)
			)
			(layer "F.Fab")
		)
		(fp_line
			(start 0.120396 0.3048)
			(end 0.120396 0.2794)
			(stroke
				(width 0.1)
				(type default)
			)
			(layer "F.Fab")
		)
		(fp_line
			(start -0.12065 0.3048)
			(end -0.67945 0.3048)
			(stroke
				(width 0.1)
				(type default)
			)
			(layer "F.Fab")
		)
		(fp_line
			(start -0.67945 0.3048)
			(end -0.67945 -0.305054)
			(stroke
				(width 0.1)
				(type default)
			)
			(layer "F.Fab")
		)
		(pad "1" smd circle
			(at -0.40005 0 90)
			(size 0 0)
			(layers "F.Cu" "F.Mask" "F.Paste")
			(net "SMB_BIC_I2C9_MUX0_SSD5_R_SCL")
		)
		(pad "2" smd circle
			(at 0.40005 0 90)
			(size 0 0)
			(layers "F.Cu" "F.Mask" "F.Paste")
			(net "SMB_ISO_SSD5_SCL")
		)
	)
)
